FILE_TYPE = CONNECTIVITY;
{Allegro Design Entry HDL 17.2-2016 S081 (4005846) 1/11/2022}
"PAGE_NUMBER" = 109;
0"NC";
1"P3V3_AUX\g";
2"P12V_S3_AUX_CPU1_NVDIMM\g";
3"P12V_S3_AUX_CPU1_NVDIMM\g";
4"P3V3_AUX\g";
5"GND\g";
6"GND\g";
7"GND\g";
8"GND\g";
9"GND\g";
10"M_F_CPU1_SA_DQ<31:0>";
11"M_F_CPU1_SA_CB<7:0>";
12"M_F_CPU1_SB_CB<7:0>";
13"M_F_CPU1_SA_CA<6:0>";
14"M_F_CPU1_SB_CA<6:0>";
15"M_F_CPU1_SB_DQ<31:0>";
16"M_F_CPU1_SB_DQS_DP<9:0>";
17"M_F_CPU1_SA_DQS_DP<9:0>";
18"M_F_CPU1_SB_DQS_DN<9:0>";
19"M_F_CPU1_SA_DQS_DN<9:0>";
20"RST_M_EF_CPU1_FPGA_N";
21"PD_CHF_CPU1_DIMM2_SAA";
22"I3C_SPD_DDREFGH_CPU1_LVC1_SDA";
23"I3C_SPD_DDREFGH_CPU1_LVC1_SCL_R4";
24"M_F_CPU1_ALERT_N";
25"I3C_SPD_DDREFGH_CPU1_LVC1_SCL";
26"PWRGD_CHF_CPU1_DIMM2";
27"M_F_CPU1_SA_DQS_DN<9>";
28"M_F_CPU1_SA_DQS_DN<8>";
29"M_F_CPU1_SA_DQS_DN<7>";
30"M_F_CPU1_SA_DQS_DN<6>";
31"M_F_CPU1_SA_DQS_DN<5>";
32"M_F_CPU1_SA_DQS_DN<4>";
33"M_F_CPU1_SA_DQS_DN<3>";
34"M_F_CPU1_SA_DQS_DN<2>";
35"M_F_CPU1_SA_DQS_DN<1>";
36"M_F_CPU1_SA_DQS_DN<0>";
37"M_F_CPU1_SB_DQS_DN<9>";
38"M_F_CPU1_SB_DQS_DN<8>";
39"M_F_CPU1_SB_DQS_DN<7>";
40"M_F_CPU1_SB_DQS_DN<5>";
41"M_F_CPU1_SB_DQS_DN<6>";
42"M_F_CPU1_SB_DQS_DN<4>";
43"M_F_CPU1_SB_DQS_DN<3>";
44"M_F_CPU1_SB_DQS_DN<2>";
45"M_F_CPU1_SB_DQS_DN<1>";
46"M_F_CPU1_SB_DQS_DN<0>";
47"M_F_CPU1_SA_DQS_DP<8>";
48"M_F_CPU1_SA_DQS_DP<9>";
49"M_F_CPU1_SA_DQS_DP<6>";
50"M_F_CPU1_SA_DQS_DP<7>";
51"M_F_CPU1_SA_DQS_DP<3>";
52"M_F_CPU1_SA_DQS_DP<4>";
53"M_F_CPU1_SA_DQS_DP<5>";
54"M_F_CPU1_SA_DQS_DP<1>";
55"M_F_CPU1_SA_DQS_DP<2>";
56"M_F_CPU1_SB_DQS_DP<9>";
57"M_F_CPU1_SA_DQS_DP<0>";
58"M_F_CPU1_SB_DQS_DP<8>";
59"M_F_CPU1_SB_DQS_DP<6>";
60"M_F_CPU1_SB_DQS_DP<7>";
61"M_F_CPU1_SB_DQS_DP<4>";
62"M_F_CPU1_SB_DQS_DP<5>";
63"M_F_CPU1_SB_DQS_DP<3>";
64"M_F_CPU1_SB_DQS_DP<1>";
65"M_F_CPU1_SB_DQS_DP<2>";
66"M_F_CPU1_SB_DQS_DP<0>";
67"M_F_CPU1_SB_CA<0>";
68"M_F_CPU1_SA_DQ<14>";
69"M_F_CPU1_SA_DQ<17>";
70"M_F_CPU1_SB_CA<3>";
71"M_F_CPU1_CLK_DP<1>";
72"M_F_CPU1_SB_CS_N<2>";
73"M_F_CPU1_SB_CS_N<3>";
74"M_F_CPU1_SA_DQ<13>";
75"M_F_CPU1_SA_DQ<9>";
76"M_F_CPU1_CLK_DN<1>";
77"M_F_CPU1_SA_DQ<18>";
78"M_F_CPU1_SA_DQ<1>";
79"M_F_CPU1_SB_DQ<25>";
80"M_F_CPU1_SB_DQ<24>";
81"M_F_CPU1_SB_DQ<12>";
82"TP_CHF_CPU1_DIMM2_FRU_0";
83"TP_CHF_CPU1_DIMM2_FRU_1";
84"TP_CHF_CPU1_DIMM2_FRU_2";
85"TP_CHF_CPU1_DIMM2_FRU_3";
86"TP_CHF_CPU1_DIMM2_FRU_4";
87"TP_CHF_CPU1_DIMM2_FRU_5";
88"TP_CHF_CPU1_DIMM2_FRU_6";
89"M_F_CPU1_SB_PAR";
90"M_F_CPU1_SA_PAR";
91"M_F_CPU1_SB_RSP<1>";
92"M_F_CPU1_SA_RSP<1>";
93"M_F_CPU1_SB_DQ<0>";
94"M_F_CPU1_SB_DQ<1>";
95"M_F_CPU1_SB_DQ<2>";
96"M_F_CPU1_SB_DQ<3>";
97"M_F_CPU1_SB_DQ<4>";
98"M_F_CPU1_SB_DQ<5>";
99"M_F_CPU1_SB_DQ<6>";
100"M_F_CPU1_SB_DQ<7>";
101"M_F_CPU1_SB_DQ<8>";
102"M_F_CPU1_SB_DQ<9>";
103"M_F_CPU1_SB_DQ<10>";
104"M_F_CPU1_SB_DQ<11>";
105"M_F_CPU1_SB_DQ<13>";
106"M_F_CPU1_SB_DQ<14>";
107"M_F_CPU1_SB_DQ<15>";
108"M_F_CPU1_SB_DQ<16>";
109"M_F_CPU1_SB_DQ<17>";
110"M_F_CPU1_SB_DQ<18>";
111"M_F_CPU1_SB_DQ<19>";
112"M_F_CPU1_SB_DQ<20>";
113"M_F_CPU1_SB_DQ<21>";
114"M_F_CPU1_SB_DQ<22>";
115"M_F_CPU1_SB_DQ<23>";
116"M_F_CPU1_SB_DQ<26>";
117"M_F_CPU1_SB_DQ<27>";
118"M_F_CPU1_SB_DQ<28>";
119"M_F_CPU1_SB_DQ<29>";
120"M_F_CPU1_SB_DQ<30>";
121"M_F_CPU1_SB_DQ<31>";
122"M_F_CPU1_SA_DQ<0>";
123"M_F_CPU1_SA_DQ<2>";
124"M_F_CPU1_SA_DQ<3>";
125"M_F_CPU1_SA_DQ<4>";
126"M_F_CPU1_SA_DQ<5>";
127"M_F_CPU1_SA_DQ<6>";
128"M_F_CPU1_SA_DQ<7>";
129"M_F_CPU1_SA_DQ<8>";
130"M_F_CPU1_SA_DQ<10>";
131"M_F_CPU1_SA_DQ<11>";
132"M_F_CPU1_SA_DQ<12>";
133"M_F_CPU1_SA_DQ<15>";
134"M_F_CPU1_SA_DQ<16>";
135"M_F_CPU1_SA_DQ<19>";
136"M_F_CPU1_SA_DQ<20>";
137"M_F_CPU1_SA_DQ<21>";
138"M_F_CPU1_SA_DQ<22>";
139"M_F_CPU1_SA_DQ<23>";
140"M_F_CPU1_SA_DQ<24>";
141"M_F_CPU1_SA_DQ<25>";
142"M_F_CPU1_SA_DQ<26>";
143"M_F_CPU1_SA_DQ<27>";
144"M_F_CPU1_SA_DQ<28>";
145"M_F_CPU1_SA_DQ<29>";
146"M_F_CPU1_SA_DQ<30>";
147"M_F_CPU1_SA_CS_N<3>";
148"M_F_CPU1_SA_CS_N<2>";
149"M_F_CPU1_SB_CB<0>";
150"M_F_CPU1_SB_CB<1>";
151"M_F_CPU1_SB_CB<2>";
152"M_F_CPU1_SB_CB<3>";
153"M_F_CPU1_SB_CB<4>";
154"M_F_CPU1_SB_CB<5>";
155"M_F_CPU1_SB_CB<6>";
156"M_F_CPU1_SA_CB<0>";
157"M_F_CPU1_SA_CB<2>";
158"M_F_CPU1_SA_CB<3>";
159"M_F_CPU1_SA_CB<5>";
160"M_F_CPU1_SA_CB<6>";
161"M_F_CPU1_SB_CA<6>";
162"M_F_CPU1_SA_CA<6>";
163"M_F_CPU1_SB_CA<5>";
164"M_F_CPU1_SA_CA<5>";
165"M_F_CPU1_SB_CA<4>";
166"M_F_CPU1_SA_CA<4>";
167"M_F_CPU1_SA_CA<3>";
168"M_F_CPU1_SB_CA<2>";
169"M_F_CPU1_SA_CA<2>";
170"M_F_CPU1_SB_CA<1>";
171"M_F_CPU1_SA_CA<1>";
172"M_F_CPU1_SA_CA<0>";
173"M_F_CPU1_SB_CB<7>";
174"M_F_CPU1_SA_CB<1>";
175"M_F_CPU1_SA_CB<4>";
176"M_F_CPU1_SA_CB<7>";
177"M_F_CPU1_SA_DQ<31>";
178"PD_CHF_CPU1_DIMM2_SAA";
%"TAP"
"1","(-800,3700)","0","standard","I100";
;
CDS_LIB"standard"
BODY_TYPE"PLUMBING"
HDL_TAP"TRUE";
"B \NAC \NWC"10;
"S \NAC"
BN"21"137;
%"TAP"
"1","(-800,3650)","0","standard","I101";
;
CDS_LIB"standard"
BODY_TYPE"PLUMBING"
HDL_TAP"TRUE";
"B \NAC \NWC"10;
"S \NAC"
BN"20"136;
%"TAP"
"1","(-800,3750)","0","standard","I102";
;
CDS_LIB"standard"
BODY_TYPE"PLUMBING"
HDL_TAP"TRUE";
"B \NAC \NWC"10;
"S \NAC"
BN"22"138;
%"TAP"
"1","(-800,3800)","0","standard","I103";
;
CDS_LIB"standard"
BODY_TYPE"PLUMBING"
HDL_TAP"TRUE";
"B \NAC \NWC"10;
"S \NAC"
BN"23"139;
%"TAP"
"1","(-800,3850)","0","standard","I104";
;
CDS_LIB"standard"
BODY_TYPE"PLUMBING"
HDL_TAP"TRUE";
"B \NAC \NWC"10;
"S \NAC"
BN"24"140;
%"TAP"
"1","(-2450,3950)","2","standard","I106";
;
CDS_LIB"standard"
BODY_TYPE"PLUMBING"
HDL_TAP"TRUE";
"B \NAC \NWC"13;
"S \NAC"
BN"1"171;
%"TAP"
"1","(-2450,3900)","2","standard","I107";
;
CDS_LIB"standard"
BODY_TYPE"PLUMBING"
HDL_TAP"TRUE";
"B \NAC \NWC"13;
"S \NAC"
BN"0"172;
%"TAP"
"1","(-2450,4000)","2","standard","I108";
;
CDS_LIB"standard"
BODY_TYPE"PLUMBING"
HDL_TAP"TRUE";
"B \NAC \NWC"13;
"S \NAC"
BN"2"169;
%"TAP"
"1","(-2450,4100)","2","standard","I109";
;
CDS_LIB"standard"
BODY_TYPE"PLUMBING"
HDL_TAP"TRUE";
"B \NAC \NWC"13;
"S \NAC"
BN"4"166;
%"TAP"
"1","(-2450,4050)","2","standard","I110";
;
CDS_LIB"standard"
BODY_TYPE"PLUMBING"
HDL_TAP"TRUE";
"B \NAC \NWC"13;
"S \NAC"
BN"3"167;
%"TAP"
"1","(-2450,4200)","2","standard","I111";
;
CDS_LIB"standard"
BODY_TYPE"PLUMBING"
HDL_TAP"TRUE";
"B \NAC \NWC"13;
"S \NAC"
BN"6"162;
%"TAP"
"1","(-2450,4150)","2","standard","I112";
;
CDS_LIB"standard"
BODY_TYPE"PLUMBING"
HDL_TAP"TRUE";
"B \NAC \NWC"13;
"S \NAC"
BN"5"164;
%"TAP"
"1","(-800,3950)","0","standard","I113";
;
CDS_LIB"standard"
BODY_TYPE"PLUMBING"
HDL_TAP"TRUE";
"B \NAC \NWC"10;
"S \NAC"
BN"26"142;
%"TAP"
"1","(-800,3900)","0","standard","I114";
;
CDS_LIB"standard"
BODY_TYPE"PLUMBING"
HDL_TAP"TRUE";
"B \NAC \NWC"10;
"S \NAC"
BN"25"141;
%"TAP"
"1","(-800,4050)","0","standard","I115";
;
CDS_LIB"standard"
BODY_TYPE"PLUMBING"
HDL_TAP"TRUE";
"B \NAC \NWC"10;
"S \NAC"
BN"28"144;
%"TAP"
"1","(-800,4100)","0","standard","I116";
;
CDS_LIB"standard"
BODY_TYPE"PLUMBING"
HDL_TAP"TRUE";
"B \NAC \NWC"10;
"S \NAC"
BN"29"145;
%"TAP"
"1","(-800,4000)","0","standard","I117";
;
CDS_LIB"standard"
BODY_TYPE"PLUMBING"
HDL_TAP"TRUE";
"B \NAC \NWC"10;
"S \NAC"
BN"27"143;
%"TAP"
"1","(-800,4150)","0","standard","I118";
;
CDS_LIB"standard"
BODY_TYPE"PLUMBING"
HDL_TAP"TRUE";
"B \NAC \NWC"10;
"S \NAC"
BN"30"146;
%"TAP"
"1","(-800,4200)","0","standard","I119";
;
CDS_LIB"standard"
BODY_TYPE"PLUMBING"
HDL_TAP"TRUE";
"B \NAC \NWC"10;
"S \NAC"
BN"31"177;
%"UNIVERSAL_GND"
"1","(925,-50)","0","logical_power","I120";
;
HDL_POWER"GND"
CDS_LIB"logical_power";
"A"5;
%"Q_CAP"
"1","(925,325)","0","pure_quanta","I121";
;
PART_NUMBER"CH5221MEB00"
PACK_TYPE"C0402"
TOLERANCE"20%"
MATERIAL"X6S"
VALUE"2.2UF"
VOLTAGE"6.3V"
$LOCATION"C84"
CDS_LIB"pure_quanta"
$LOCATION"C84"
$LOCATION"C84"
CDS_LOCATION"C84"
$SEC"1"
CDS_SEC"1";
"B"
$PN"2"5;
"A"
$PN"1"1;
%"VCC_CORE"
"1","(925,650)","0","logical_power","I122";
;
HDL_POWER"P3V3_AUX"
CDS_LIB"logical_power";
"A"1;
%"Q_CAP"
"1","(1925,325)","0","pure_quanta","I125";
;
PART_NUMBER"CH6103KEA00"
PACK_TYPE"C0805"
VALUE"10UF"
VOLTAGE"16V"
TOLERANCE"10%"
MATERIAL"X6S"
$LOCATION"C85"
CDS_LIB"pure_quanta"
$LOCATION"C85"
$LOCATION"C85"
CDS_LOCATION"C85"
$SEC"1"
CDS_SEC"1";
"B"
$PN"2"6;
"A"
$PN"1"2;
%"VCC_CORE"
"1","(1925,650)","0","logical_power","I126";
;
HDL_POWER"P12V_S3_AUX_CPU1_NVDIMM"
CDS_LIB"logical_power";
"A"2;
%"UNIVERSAL_GND"
"1","(2550,-50)","0","logical_power","I127";
;
HDL_POWER"GND"
CDS_LIB"logical_power";
"A"6;
%"Q_CAP"
"1","(2550,325)","0","pure_quanta","I128";
;
PART_NUMBER"CH6103KEA00"
TOLERANCE"10%"
VOLTAGE"16V"
VALUE"10UF"
PACK_TYPE"C0805"
MATERIAL"X6S"
$LOCATION"C86"
CDS_LIB"pure_quanta"
$LOCATION"C86"
$LOCATION"C86"
CDS_LOCATION"C86"
$SEC"1"
CDS_SEC"1";
"B"
$PN"2"6;
"A"
$PN"1"2;
%"UNIVERSAL_GND"
"1","(3625,500)","0","logical_power","I129";
;
HDL_POWER"GND"
CDS_LIB"logical_power";
"A"7;
%"TAP"
"1","(1950,2250)","0","standard","I130";
;
CDS_LIB"standard"
BODY_TYPE"PLUMBING"
HDL_TAP"TRUE";
"B \NAC \NWC"16;
"S \NAC"
BN"0"66;
%"TAP"
"1","(2125,2200)","0","standard","I131";
;
CDS_LIB"standard"
BODY_TYPE"PLUMBING"
HDL_TAP"TRUE";
"B \NAC \NWC"18;
"S \NAC"
BN"0"46;
%"TAP"
"1","(2125,2300)","0","standard","I132";
;
CDS_LIB"standard"
BODY_TYPE"PLUMBING"
HDL_TAP"TRUE";
"B \NAC \NWC"18;
"S \NAC"
BN"1"45;
%"TAP"
"1","(1950,2350)","0","standard","I133";
;
CDS_LIB"standard"
BODY_TYPE"PLUMBING"
HDL_TAP"TRUE";
"B \NAC \NWC"16;
"S \NAC"
BN"1"64;
%"TAP"
"1","(1950,2450)","0","standard","I134";
;
CDS_LIB"standard"
BODY_TYPE"PLUMBING"
HDL_TAP"TRUE";
"B \NAC \NWC"16;
"S \NAC"
BN"2"65;
%"TAP"
"1","(1950,2550)","0","standard","I135";
;
CDS_LIB"standard"
BODY_TYPE"PLUMBING"
HDL_TAP"TRUE";
"B \NAC \NWC"16;
"S \NAC"
BN"3"63;
%"TAP"
"1","(1950,2650)","0","standard","I136";
;
CDS_LIB"standard"
BODY_TYPE"PLUMBING"
HDL_TAP"TRUE";
"B \NAC \NWC"16;
"S \NAC"
BN"4"61;
%"TAP"
"1","(1950,2750)","0","standard","I137";
;
CDS_LIB"standard"
BODY_TYPE"PLUMBING"
HDL_TAP"TRUE";
"B \NAC \NWC"16;
"S \NAC"
BN"5"62;
%"TAP"
"1","(2125,2400)","0","standard","I138";
;
CDS_LIB"standard"
BODY_TYPE"PLUMBING"
HDL_TAP"TRUE";
"B \NAC \NWC"18;
"S \NAC"
BN"2"44;
%"TAP"
"1","(2125,2500)","0","standard","I139";
;
CDS_LIB"standard"
BODY_TYPE"PLUMBING"
HDL_TAP"TRUE";
"B \NAC \NWC"18;
"S \NAC"
BN"3"43;
%"TAP"
"1","(2125,2600)","0","standard","I140";
;
CDS_LIB"standard"
BODY_TYPE"PLUMBING"
HDL_TAP"TRUE";
"B \NAC \NWC"18;
"S \NAC"
BN"4"42;
%"TAP"
"1","(2125,2700)","0","standard","I141";
;
CDS_LIB"standard"
BODY_TYPE"PLUMBING"
HDL_TAP"TRUE";
"B \NAC \NWC"18;
"S \NAC"
BN"5"40;
%"TAP"
"1","(2125,2800)","0","standard","I142";
;
CDS_LIB"standard"
BODY_TYPE"PLUMBING"
HDL_TAP"TRUE";
"B \NAC \NWC"18;
"S \NAC"
BN"6"41;
%"TAP"
"1","(1950,2850)","0","standard","I143";
;
CDS_LIB"standard"
BODY_TYPE"PLUMBING"
HDL_TAP"TRUE";
"B \NAC \NWC"16;
"S \NAC"
BN"6"59;
%"TAP"
"1","(1950,2950)","0","standard","I144";
;
CDS_LIB"standard"
BODY_TYPE"PLUMBING"
HDL_TAP"TRUE";
"B \NAC \NWC"16;
"S \NAC"
BN"7"60;
%"TAP"
"1","(1950,3050)","0","standard","I145";
;
CDS_LIB"standard"
BODY_TYPE"PLUMBING"
HDL_TAP"TRUE";
"B \NAC \NWC"16;
"S \NAC"
BN"8"58;
%"TAP"
"1","(1950,3150)","0","standard","I146";
;
CDS_LIB"standard"
BODY_TYPE"PLUMBING"
HDL_TAP"TRUE";
"B \NAC \NWC"16;
"S \NAC"
BN"9"56;
%"TAP"
"1","(1950,3300)","0","standard","I147";
;
CDS_LIB"standard"
BODY_TYPE"PLUMBING"
HDL_TAP"TRUE";
"B \NAC \NWC"17;
"S \NAC"
BN"0"57;
%"TAP"
"1","(2125,2900)","0","standard","I148";
;
CDS_LIB"standard"
BODY_TYPE"PLUMBING"
HDL_TAP"TRUE";
"B \NAC \NWC"18;
"S \NAC"
BN"7"39;
%"TAP"
"1","(2125,3100)","0","standard","I149";
;
CDS_LIB"standard"
BODY_TYPE"PLUMBING"
HDL_TAP"TRUE";
"B \NAC \NWC"18;
"S \NAC"
BN"9"37;
%"TAP"
"1","(2125,3000)","0","standard","I150";
;
CDS_LIB"standard"
BODY_TYPE"PLUMBING"
HDL_TAP"TRUE";
"B \NAC \NWC"18;
"S \NAC"
BN"8"38;
%"TAP"
"1","(2125,3250)","0","standard","I151";
;
CDS_LIB"standard"
BODY_TYPE"PLUMBING"
HDL_TAP"TRUE";
"B \NAC \NWC"19;
"S \NAC"
BN"0"36;
%"TAP"
"1","(2125,3350)","0","standard","I152";
;
CDS_LIB"standard"
BODY_TYPE"PLUMBING"
HDL_TAP"TRUE";
"B \NAC \NWC"19;
"S \NAC"
BN"1"35;
%"TAP"
"1","(1950,3400)","0","standard","I153";
;
CDS_LIB"standard"
BODY_TYPE"PLUMBING"
HDL_TAP"TRUE";
"B \NAC \NWC"17;
"S \NAC"
BN"1"54;
%"TAP"
"1","(1950,3600)","0","standard","I154";
;
CDS_LIB"standard"
BODY_TYPE"PLUMBING"
HDL_TAP"TRUE";
"B \NAC \NWC"17;
"S \NAC"
BN"3"51;
%"TAP"
"1","(1950,3500)","0","standard","I155";
;
CDS_LIB"standard"
BODY_TYPE"PLUMBING"
HDL_TAP"TRUE";
"B \NAC \NWC"17;
"S \NAC"
BN"2"55;
%"TAP"
"1","(1950,3700)","0","standard","I156";
;
CDS_LIB"standard"
BODY_TYPE"PLUMBING"
HDL_TAP"TRUE";
"B \NAC \NWC"17;
"S \NAC"
BN"4"52;
%"TAP"
"1","(1950,3800)","0","standard","I157";
;
CDS_LIB"standard"
BODY_TYPE"PLUMBING"
HDL_TAP"TRUE";
"B \NAC \NWC"17;
"S \NAC"
BN"5"53;
%"TAP"
"1","(2125,3450)","0","standard","I158";
;
CDS_LIB"standard"
BODY_TYPE"PLUMBING"
HDL_TAP"TRUE";
"B \NAC \NWC"19;
"S \NAC"
BN"2"34;
%"TAP"
"1","(2125,3550)","0","standard","I159";
;
CDS_LIB"standard"
BODY_TYPE"PLUMBING"
HDL_TAP"TRUE";
"B \NAC \NWC"19;
"S \NAC"
BN"3"33;
%"TAP"
"1","(2125,3650)","0","standard","I160";
;
CDS_LIB"standard"
BODY_TYPE"PLUMBING"
HDL_TAP"TRUE";
"B \NAC \NWC"19;
"S \NAC"
BN"4"32;
%"TAP"
"1","(2125,3850)","0","standard","I161";
;
CDS_LIB"standard"
BODY_TYPE"PLUMBING"
HDL_TAP"TRUE";
"B \NAC \NWC"19;
"S \NAC"
BN"6"30;
%"TAP"
"1","(2125,3750)","0","standard","I162";
;
CDS_LIB"standard"
BODY_TYPE"PLUMBING"
HDL_TAP"TRUE";
"B \NAC \NWC"19;
"S \NAC"
BN"5"31;
%"TAP"
"1","(1950,3900)","0","standard","I166";
;
CDS_LIB"standard"
BODY_TYPE"PLUMBING"
HDL_TAP"TRUE";
"B \NAC \NWC"17;
"S \NAC"
BN"6"49;
%"TAP"
"1","(1950,4100)","0","standard","I167";
;
CDS_LIB"standard"
BODY_TYPE"PLUMBING"
HDL_TAP"TRUE";
"B \NAC \NWC"17;
"S \NAC"
BN"8"47;
%"TAP"
"1","(1950,4000)","0","standard","I168";
;
CDS_LIB"standard"
BODY_TYPE"PLUMBING"
HDL_TAP"TRUE";
"B \NAC \NWC"17;
"S \NAC"
BN"7"50;
%"TAP"
"1","(1950,4200)","0","standard","I169";
;
CDS_LIB"standard"
BODY_TYPE"PLUMBING"
HDL_TAP"TRUE";
"B \NAC \NWC"17;
"S \NAC"
BN"9"48;
%"TAP"
"1","(2125,3950)","0","standard","I170";
;
CDS_LIB"standard"
BODY_TYPE"PLUMBING"
HDL_TAP"TRUE";
"B \NAC \NWC"19;
"S \NAC"
BN"7"29;
%"TAP"
"1","(2125,4050)","0","standard","I171";
;
CDS_LIB"standard"
BODY_TYPE"PLUMBING"
HDL_TAP"TRUE";
"B \NAC \NWC"19;
"S \NAC"
BN"8"28;
%"TAP"
"1","(2125,4150)","0","standard","I172";
;
CDS_LIB"standard"
BODY_TYPE"PLUMBING"
HDL_TAP"TRUE";
"B \NAC \NWC"19;
"S \NAC"
BN"9"27;
%"VCC_CORE"
"1","(3625,4750)","0","logical_power","I175";
;
HDL_POWER"P12V_S3_AUX_CPU1_NVDIMM"
CDS_LIB"logical_power";
"A"3;
%"SCONN288_ADR50017P087CC"
"3","(4475,2575)","0","pure_quanta","I176";
;
PART_NUMBER"DFHST8FS460"
MATERIAL"IO"
PART_TYPE"SMLF"
VALUE"SCONN288_ADR50017-P087CC"
$LOCATION"J28"
NEEDS_NO_SIZE"TRUE"
CDS_LMAN_SYM_OUTLINE"-450,1775,450,-1775"
CDS_LIB"pure_quanta"
CDS_LOCATION"J28"
$SEC"3"
CDS_SEC"3";
"G3"
$PN"G3"8;
"G2"
$PN"G2"8;
"G1"
$PN"G1"8;
"VSS62"
$PN"141"8;
"VSS61"
$PN"139"8;
"VSS60"
$PN"136"8;
"VSS58"
$PN"132"8;
"VSS104"
$PN"240"7;
"VSS102"
$PN"235"7;
"VSS100"
$PN"230"7;
"VIN_BULK2"
$PN"146"3;
"VIN_BULK1"
$PN"145"3;
"VIN_BULK0"
$PN"1"3;
"VSS126"
$PN"288"7;
"VSS125"
$PN"286"7;
"VSS124"
$PN"284"7;
"VSS123"
$PN"281"7;
"VSS122"
$PN"279"7;
"VSS121"
$PN"277"7;
"VSS120"
$PN"275"7;
"VSS119"
$PN"273"7;
"VSS118"
$PN"270"7;
"VSS117"
$PN"268"7;
"VSS116"
$PN"266"7;
"VSS115"
$PN"264"7;
"VSS114"
$PN"262"7;
"VSS113"
$PN"259"7;
"VSS112"
$PN"257"7;
"VSS111"
$PN"255"7;
"VSS110"
$PN"253"7;
"VSS109"
$PN"251"7;
"VSS108"
$PN"248"7;
"VSS107"
$PN"246"7;
"VSS106"
$PN"244"7;
"VSS105"
$PN"242"7;
"VSS103"
$PN"237"7;
"VSS101"
$PN"233"7;
"VSS99"
$PN"228"7;
"VSS98"
$PN"226"7;
"VSS97"
$PN"224"7;
"VSS96"
$PN"222"7;
"VSS95"
$PN"219"7;
"VSS94"
$PN"216"7;
"VSS93"
$PN"214"7;
"VSS92"
$PN"212"7;
"VSS91"
$PN"210"7;
"VSS90"
$PN"208"7;
"VSS89"
$PN"206"7;
"VSS88"
$PN"204"7;
"VSS87"
$PN"202"7;
"VSS86"
$PN"199"7;
"VSS85"
$PN"197"7;
"VSS84"
$PN"195"7;
"VSS83"
$PN"193"7;
"VSS82"
$PN"191"7;
"VSS81"
$PN"188"7;
"VSS80"
$PN"186"7;
"VSS79"
$PN"184"7;
"VSS78"
$PN"182"7;
"VSS77"
$PN"180"7;
"VSS76"
$PN"177"7;
"VSS75"
$PN"175"7;
"VSS74"
$PN"173"7;
"VSS73"
$PN"171"7;
"VSS72"
$PN"169"7;
"VSS71"
$PN"166"7;
"VSS70"
$PN"164"7;
"VSS69"
$PN"162"7;
"VSS68"
$PN"160"7;
"VSS67"
$PN"158"7;
"VSS66"
$PN"155"7;
"VSS65"
$PN"153"7;
"VSS64"
$PN"151"7;
"VSS63"
$PN"143"8;
"VSS59"
$PN"134"8;
"VSS57"
$PN"130"8;
"VSS56"
$PN"128"8;
"VSS55"
$PN"125"8;
"VSS54"
$PN"123"8;
"VSS53"
$PN"121"8;
"VSS52"
$PN"119"8;
"VSS51"
$PN"117"8;
"VSS50"
$PN"114"8;
"VSS49"
$PN"112"8;
"VSS48"
$PN"110"8;
"VSS47"
$PN"108"8;
"VSS46"
$PN"106"8;
"VSS45"
$PN"103"8;
"VSS44"
$PN"101"8;
"VSS43"
$PN"99"8;
"VSS42"
$PN"97"8;
"VSS41"
$PN"95"8;
"VSS40"
$PN"92"8;
"VSS39"
$PN"90"8;
"VSS38"
$PN"88"8;
"VSS37"
$PN"85"8;
"VSS36"
$PN"83"8;
"VSS35"
$PN"81"8;
"VSS34"
$PN"79"8;
"VSS33"
$PN"77"8;
"VSS32"
$PN"75"8;
"VSS31"
$PN"73"8;
"VSS30"
$PN"71"8;
"VSS29"
$PN"69"8;
"VSS28"
$PN"67"8;
"VSS27"
$PN"65"8;
"VSS26"
$PN"63"8;
"VSS25"
$PN"61"8;
"VSS24"
$PN"59"8;
"VSS23"
$PN"57"8;
"VSS22"
$PN"54"8;
"VSS21"
$PN"52"8;
"VSS20"
$PN"50"8;
"VSS19"
$PN"48"8;
"VSS18"
$PN"46"8;
"VSS17"
$PN"43"8;
"VSS16"
$PN"41"8;
"VSS15"
$PN"39"8;
"VSS14"
$PN"37"8;
"VSS13"
$PN"35"8;
"VSS12"
$PN"32"8;
"VSS11"
$PN"30"8;
"VSS10"
$PN"28"8;
"VSS9"
$PN"26"8;
"VSS8"
$PN"24"8;
"VSS7"
$PN"21"8;
"VSS6"
$PN"19"8;
"VSS5"
$PN"17"8;
"VSS4"
$PN"15"8;
"VSS3"
$PN"13"8;
"VSS2"
$PN"10"8;
"VSS1"
$PN"8"8;
"VSS0"
$PN"6"8;
%"UNIVERSAL_GND"
"1","(5325,500)","0","logical_power","I177";
;
HDL_POWER"GND"
CDS_LIB"logical_power";
"A"8;
%"SCONN288_ADR50017P087CC"
"2","(1050,3200)","0","pure_quanta","I178";
;
PART_NUMBER"DFHST8FS460"
PART_TYPE"SMLF"
MATERIAL"IO"
VALUE"SCONN288_ADR50017-P087CC"
LOCATION"J28"
NEEDS_NO_SIZE"TRUE"
CDS_LMAN_SYM_OUTLINE"-600,1150,600,-1150"
CDS_LIB"pure_quanta"
$SEC"2"
CDS_SEC"2";
"DQS7_A_C||TDQS7_A_C \B"
$PN"178"29;
"DQS6_A_T||TDQS6_A_T"
$PN"168"49;
"DQS8_B_T||TDQS8_B_T"
$PN"283"58;
"DQS8_B_C||TDQS8_B_C \B"
$PN"282"38;
"DQS7_B_T||TDQS7_B_T"
$PN"272"60;
"DQS0_A_C \B"
$PN"12"36;
"DQS0_A_T"
$PN"11"57;
"DQS0_B_C \B"
$PN"105"46;
"DQS0_B_T"
$PN"104"66;
"DQS1_A_C \B"
$PN"23"35;
"DQS1_A_T"
$PN"22"54;
"DQS1_B_C \B"
$PN"116"45;
"DQS1_B_T"
$PN"115"64;
"DQS2_A_C \B"
$PN"34"34;
"DQS2_A_T"
$PN"33"55;
"DQS2_B_C \B"
$PN"127"44;
"DQS2_B_T"
$PN"126"65;
"DQS3_A_C \B"
$PN"45"33;
"DQS3_A_T"
$PN"44"51;
"DQS3_B_C \B"
$PN"138"43;
"DQS3_B_T"
$PN"137"63;
"DQS4_A_C \B"
$PN"56"32;
"DQS4_A_T"
$PN"55"52;
"DQS4_B_C \B"
$PN"238"42;
"DQS4_B_T"
$PN"239"61;
"DQS5_A_C||TDQS5_A_C||DQS5_A_T||TDQS5_A_T \B"
$PN"156"31;
"DQS5_A_T||TDQS5_A_T"
$PN"157"53;
"DQS5_B_C||TDQS5_B_C \B"
$PN"249"40;
"DQS5_B_T||TDQS5_B_T"
$PN"250"62;
"DQS6_A_C||TDQS6_A_C||DQS6_A_T||TDQS6_A_T \B"
$PN"167"30;
"DQS6_B_C||TDQS6_B_C \B"
$PN"260"41;
"DQS6_B_T||TDQS6_B_T"
$PN"261"59;
"DQS7_A_T||TDQS7_A_T"
$PN"179"50;
"DQS7_B_C||TDQS7_B_C \B"
$PN"271"39;
"DQS8_A_C||TDQS8_A_C \B"
$PN"189"28;
"DQS8_A_T||TDQS8_A_T"
$PN"190"47;
"DQS9_A_C||TDQS9_A_C \B"
$PN"200"27;
"DQS9_A_T||TDQS9_A_T"
$PN"201"48;
"DQS9_B_C||TDQS9_B_C \B"
$PN"94"37;
"DQS9_B_T||TDQS9_B_T||DBI4_B_N"
$PN"93"56;
%"Q_RES"
"1","(-3475,1500)","0","pure_quanta","I180";
;
PART_NUMBER"CS04992FB07"
VALUE"49.9"
MATERIAL"CHIP"
$LOCATION"R3902"
CDS_LIB"pure_quanta"
PACK_TYPE"0402LF"
TOLERANCE"1%"
WATTAGE"1/16W"
CDS_LOCATION"R3902"
$SEC"1"
CDS_SEC"1";
"B"
$PN"2"25;
"A"
$PN"1"23;
%"VCC_CORE"
"1","(-3275,2075)","0","logical_power","I21";
;
HDL_POWER"P3V3_AUX"
CDS_LIB"logical_power";
"A"4;
%"TAP"
"1","(-2450,2050)","2","standard","I22";
;
CDS_LIB"standard"
BODY_TYPE"PLUMBING"
HDL_TAP"TRUE";
"B \NAC \NWC"12;
"S \NAC"
BN"1"150;
%"TAP"
"1","(-2450,2000)","2","standard","I23";
;
CDS_LIB"standard"
BODY_TYPE"PLUMBING"
HDL_TAP"TRUE";
"B \NAC \NWC"12;
"S \NAC"
BN"0"149;
%"TAP"
"1","(-2450,2100)","2","standard","I24";
;
CDS_LIB"standard"
BODY_TYPE"PLUMBING"
HDL_TAP"TRUE";
"B \NAC \NWC"12;
"S \NAC"
BN"2"151;
%"TAP"
"1","(-2450,2150)","2","standard","I25";
;
CDS_LIB"standard"
BODY_TYPE"PLUMBING"
HDL_TAP"TRUE";
"B \NAC \NWC"12;
"S \NAC"
BN"3"152;
%"TAP"
"1","(-2450,2200)","2","standard","I26";
;
CDS_LIB"standard"
BODY_TYPE"PLUMBING"
HDL_TAP"TRUE";
"B \NAC \NWC"12;
"S \NAC"
BN"4"153;
%"TAP"
"1","(-2450,2250)","2","standard","I27";
;
CDS_LIB"standard"
BODY_TYPE"PLUMBING"
HDL_TAP"TRUE";
"B \NAC \NWC"12;
"S \NAC"
BN"5"154;
%"TAP"
"1","(-2450,2300)","2","standard","I28";
;
CDS_LIB"standard"
BODY_TYPE"PLUMBING"
HDL_TAP"TRUE";
"B \NAC \NWC"12;
"S \NAC"
BN"6"155;
%"TAP"
"1","(-2450,2450)","2","standard","I29";
;
CDS_LIB"standard"
BODY_TYPE"PLUMBING"
HDL_TAP"TRUE";
"B \NAC \NWC"11;
"S \NAC"
BN"0"156;
%"TAP"
"1","(-2450,2350)","2","standard","I30";
;
CDS_LIB"standard"
BODY_TYPE"PLUMBING"
HDL_TAP"TRUE";
"B \NAC \NWC"12;
"S \NAC"
BN"7"173;
%"TAP"
"1","(-2450,2550)","2","standard","I31";
;
CDS_LIB"standard"
BODY_TYPE"PLUMBING"
HDL_TAP"TRUE";
"B \NAC \NWC"11;
"S \NAC"
BN"2"157;
%"TAP"
"1","(-2450,2500)","2","standard","I32";
;
CDS_LIB"standard"
BODY_TYPE"PLUMBING"
HDL_TAP"TRUE";
"B \NAC \NWC"11;
"S \NAC"
BN"1"174;
%"TAP"
"1","(-2450,2600)","2","standard","I33";
;
CDS_LIB"standard"
BODY_TYPE"PLUMBING"
HDL_TAP"TRUE";
"B \NAC \NWC"11;
"S \NAC"
BN"3"158;
%"TAP"
"1","(-2450,2650)","2","standard","I34";
;
CDS_LIB"standard"
BODY_TYPE"PLUMBING"
HDL_TAP"TRUE";
"B \NAC \NWC"11;
"S \NAC"
BN"4"175;
%"TAP"
"1","(-2450,2700)","2","standard","I35";
;
CDS_LIB"standard"
BODY_TYPE"PLUMBING"
HDL_TAP"TRUE";
"B \NAC \NWC"11;
"S \NAC"
BN"5"159;
%"TAP"
"1","(-2450,2800)","2","standard","I36";
;
CDS_LIB"standard"
BODY_TYPE"PLUMBING"
HDL_TAP"TRUE";
"B \NAC \NWC"11;
"S \NAC"
BN"7"176;
%"TAP"
"1","(-2450,2750)","2","standard","I37";
;
CDS_LIB"standard"
BODY_TYPE"PLUMBING"
HDL_TAP"TRUE";
"B \NAC \NWC"11;
"S \NAC"
BN"6"160;
%"TAP"
"1","(-2450,3500)","2","standard","I38";
;
CDS_LIB"standard"
BODY_TYPE"PLUMBING"
HDL_TAP"TRUE";
"B \NAC \NWC"14;
"S \NAC"
BN"0"67;
%"TAP"
"1","(-2450,3550)","2","standard","I39";
;
CDS_LIB"standard"
BODY_TYPE"PLUMBING"
HDL_TAP"TRUE";
"B \NAC \NWC"14;
"S \NAC"
BN"1"170;
%"TAP"
"1","(-2450,3600)","2","standard","I40";
;
CDS_LIB"standard"
BODY_TYPE"PLUMBING"
HDL_TAP"TRUE";
"B \NAC \NWC"14;
"S \NAC"
BN"2"168;
%"TAP"
"1","(-2450,3650)","2","standard","I41";
;
CDS_LIB"standard"
BODY_TYPE"PLUMBING"
HDL_TAP"TRUE";
"B \NAC \NWC"14;
"S \NAC"
BN"3"70;
%"TAP"
"1","(-2450,3700)","2","standard","I42";
;
CDS_LIB"standard"
BODY_TYPE"PLUMBING"
HDL_TAP"TRUE";
"B \NAC \NWC"14;
"S \NAC"
BN"4"165;
%"TAP"
"1","(-2450,3800)","2","standard","I43";
;
CDS_LIB"standard"
BODY_TYPE"PLUMBING"
HDL_TAP"TRUE";
"B \NAC \NWC"14;
"S \NAC"
BN"6"161;
%"TAP"
"1","(-2450,3750)","2","standard","I44";
;
CDS_LIB"standard"
BODY_TYPE"PLUMBING"
HDL_TAP"TRUE";
"B \NAC \NWC"14;
"S \NAC"
BN"5"163;
%"UNIVERSAL_GND"
"1","(-2225,-175)","0","logical_power","I45";
;
HDL_POWER"GND"
CDS_LIB"logical_power";
"A"9;
%"Q_RES"
"2","(-2225,50)","0","pure_quanta","I46";
;
PART_NUMBER"CS33572FB01"
VALUE"35.7K"
PACK_TYPE"0402LF"
MATERIAL"CHIP"
TOLERANCE"1%"
WATTAGE"1/16W"
$LOCATION"R76"
CDS_LIB"pure_quanta"
$LOCATION"R76"
$LOCATION"R76"
CDS_LOCATION"R76"
$SEC"1"
CDS_SEC"1";
"A"
$PN"1"178;
"B"
$PN"2"9;
%"SCONN288_ADR50017P087CC"
"1","(-1625,2475)","0","pure_quanta","I47";
;
PART_NUMBER"DFHST8FS460"
MATERIAL"IO"
VALUE"SCONN288_ADR50017-P087CC"
PART_TYPE"SMLF"
$LOCATION"J28"
NEEDS_NO_SIZE"TRUE"
CDS_LMAN_SYM_OUTLINE"-450,1875,450,-1875"
CDS_LIB"pure_quanta"
CDS_LOCATION"J28"
$SEC"1"
CDS_SEC"1";
"DQ31_A"
$PN"194"177;
"CB7_A"
$PN"205"176;
"CB4_A"
$PN"58"175;
"CB1_A"
$PN"53"174;
"CB7_B"
$PN"236"173;
"ALERT_N \B"
$PN"62"24;
"CA0_A"
$PN"66"172;
"CA0_B"
$PN"76"67;
"CA1_A"
$PN"211"171;
"CA1_B"
$PN"221"170;
"CA2_A"
$PN"68"169;
"CA2_B"
$PN"78"168;
"CA3_A"
$PN"213"167;
"CA3_B"
$PN"223"70;
"CA4_A"
$PN"70"166;
"CA4_B"
$PN"80"165;
"CA5_A"
$PN"215"164;
"CA5_B"
$PN"225"163;
"CA6_A"
$PN"72"162;
"CA6_B"
$PN"82"161;
"CB6_A"
$PN"203"160;
"CB5_A"
$PN"60"159;
"CB3_A"
$PN"198"158;
"CB2_A"
$PN"196"157;
"CB0_A"
$PN"51"156;
"CB6_B"
$PN"234"155;
"CB5_B"
$PN"91"154;
"CB4_B"
$PN"89"153;
"CB3_B"
$PN"243"152;
"CB2_B"
$PN"241"151;
"CB1_B"
$PN"98"150;
"CB0_B"
$PN"96"149;
"CK_C \B"
$PN"218"76;
"CK_T"
$PN"217"71;
"CS0_A_N"
$PN"64"148;
"CS0_B_N"
$PN"84"72;
"CS1_A_N"
$PN"209"147;
"CS1_B_N"
$PN"229"73;
"DQ30_A"
$PN"192"146;
"DQ29_A"
$PN"49"145;
"DQ28_A"
$PN"47"144;
"DQ27_A"
$PN"187"143;
"DQ26_A"
$PN"185"142;
"DQ25_A"
$PN"42"141;
"DQ24_A"
$PN"40"140;
"DQ23_A"
$PN"183"139;
"DQ22_A"
$PN"181"138;
"DQ21_A"
$PN"38"137;
"DQ20_A"
$PN"36"136;
"DQ19_A"
$PN"176"135;
"DQ18_A"
$PN"174"77;
"DQ17_A"
$PN"31"69;
"DQ16_A"
$PN"29"134;
"DQ15_A"
$PN"172"133;
"DQ14_A"
$PN"170"68;
"DQ13_A"
$PN"27"74;
"DQ12_A"
$PN"25"132;
"DQ11_A"
$PN"165"131;
"DQ10_A"
$PN"163"130;
"DQ9_A"
$PN"20"75;
"DQ8_A"
$PN"18"129;
"DQ7_A"
$PN"161"128;
"DQ6_A"
$PN"159"127;
"DQ5_A"
$PN"16"126;
"DQ4_A"
$PN"14"125;
"DQ3_A"
$PN"154"124;
"DQ2_A"
$PN"152"123;
"DQ1_A"
$PN"9"78;
"DQ0_A"
$PN"7"122;
"DQ31_B"
$PN"287"121;
"DQ30_B"
$PN"285"120;
"DQ29_B"
$PN"142"119;
"DQ28_B"
$PN"140"118;
"DQ27_B"
$PN"280"117;
"DQ26_B"
$PN"278"116;
"DQ25_B"
$PN"135"79;
"DQ24_B"
$PN"133"80;
"DQ23_B"
$PN"276"115;
"DQ22_B"
$PN"274"114;
"DQ21_B"
$PN"131"113;
"DQ20_B"
$PN"129"112;
"DQ19_B"
$PN"269"111;
"DQ18_B"
$PN"267"110;
"DQ17_B"
$PN"124"109;
"DQ16_B"
$PN"122"108;
"DQ15_B"
$PN"265"107;
"DQ14_B"
$PN"263"106;
"DQ13_B"
$PN"120"105;
"DQ12_B"
$PN"118"81;
"DQ11_B"
$PN"258"104;
"DQ10_B"
$PN"256"103;
"DQ9_B"
$PN"113"102;
"DQ8_B"
$PN"111"101;
"DQ7_B"
$PN"254"100;
"DQ6_B"
$PN"252"99;
"DQ5_B"
$PN"109"98;
"DQ4_B"
$PN"107"97;
"DQ3_B"
$PN"247"96;
"DQ2_B"
$PN"245"95;
"DQ1_B"
$PN"102"94;
"DQ0_B"
$PN"100"93;
"HSA"
$PN"148"21;
"HSCL"
$PN"4"23;
"HSDA"
$PN"5"22;
"LBD||RSP_A_N"
$PN"86"92;
"LBS||RSP_B_N"
$PN"87"91;
"PAR_A"
$PN"74"90;
"PAR_B"
$PN"227"89;
"PWR_GOOD||FAIL_N"
$PN"147"26;
"RESET_N \B"
$PN"207"20;
"RFU6"
$PN"232"88;
"RFU5"
$PN"231"87;
"RFU4"
$PN"220"86;
"RFU3"
$PN"150"85;
"RFU2"
$PN"149"84;
"RFU1"
$PN"144"83;
"RFU0"
$PN"2"82;
"VIN_MGMT"
$PN"3"4;
%"TAP"
"1","(-800,1050)","0","standard","I48";
;
CDS_LIB"standard"
BODY_TYPE"PLUMBING"
HDL_TAP"TRUE";
"B \NAC \NWC"15;
"S \NAC"
BN"1"94;
%"TAP"
"1","(-800,1000)","0","standard","I49";
;
CDS_LIB"standard"
BODY_TYPE"PLUMBING"
HDL_TAP"TRUE";
"B \NAC \NWC"15;
"S \NAC"
BN"0"93;
%"TAP"
"1","(-800,1100)","0","standard","I50";
;
CDS_LIB"standard"
BODY_TYPE"PLUMBING"
HDL_TAP"TRUE";
"B \NAC \NWC"15;
"S \NAC"
BN"2"95;
%"TAP"
"1","(-800,1150)","0","standard","I51";
;
CDS_LIB"standard"
BODY_TYPE"PLUMBING"
HDL_TAP"TRUE";
"B \NAC \NWC"15;
"S \NAC"
BN"3"96;
%"TAP"
"1","(-800,1300)","0","standard","I52";
;
CDS_LIB"standard"
BODY_TYPE"PLUMBING"
HDL_TAP"TRUE";
"B \NAC \NWC"15;
"S \NAC"
BN"6"99;
%"TAP"
"1","(-800,1250)","0","standard","I53";
;
CDS_LIB"standard"
BODY_TYPE"PLUMBING"
HDL_TAP"TRUE";
"B \NAC \NWC"15;
"S \NAC"
BN"5"98;
%"TAP"
"1","(-800,1200)","0","standard","I54";
;
CDS_LIB"standard"
BODY_TYPE"PLUMBING"
HDL_TAP"TRUE";
"B \NAC \NWC"15;
"S \NAC"
BN"4"97;
%"TAP"
"1","(-800,1400)","0","standard","I55";
;
CDS_LIB"standard"
BODY_TYPE"PLUMBING"
HDL_TAP"TRUE";
"B \NAC \NWC"15;
"S \NAC"
BN"8"101;
%"TAP"
"1","(-800,1350)","0","standard","I56";
;
CDS_LIB"standard"
BODY_TYPE"PLUMBING"
HDL_TAP"TRUE";
"B \NAC \NWC"15;
"S \NAC"
BN"7"100;
%"TAP"
"1","(-800,1450)","0","standard","I57";
;
CDS_LIB"standard"
BODY_TYPE"PLUMBING"
HDL_TAP"TRUE";
"B \NAC \NWC"15;
"S \NAC"
BN"9"102;
%"TAP"
"1","(-800,1500)","0","standard","I58";
;
CDS_LIB"standard"
BODY_TYPE"PLUMBING"
HDL_TAP"TRUE";
"B \NAC \NWC"15;
"S \NAC"
BN"10"103;
%"TAP"
"1","(-800,1550)","0","standard","I59";
;
CDS_LIB"standard"
BODY_TYPE"PLUMBING"
HDL_TAP"TRUE";
"B \NAC \NWC"15;
"S \NAC"
BN"11"104;
%"TAP"
"1","(-800,1650)","0","standard","I60";
;
CDS_LIB"standard"
BODY_TYPE"PLUMBING"
HDL_TAP"TRUE";
"B \NAC \NWC"15;
"S \NAC"
BN"13"105;
%"TAP"
"1","(-800,1600)","0","standard","I61";
;
CDS_LIB"standard"
BODY_TYPE"PLUMBING"
HDL_TAP"TRUE";
"B \NAC \NWC"15;
"S \NAC"
BN"12"81;
%"TAP"
"1","(-800,1700)","0","standard","I62";
;
CDS_LIB"standard"
BODY_TYPE"PLUMBING"
HDL_TAP"TRUE";
"B \NAC \NWC"15;
"S \NAC"
BN"14"106;
%"TAP"
"1","(-800,1750)","0","standard","I63";
;
CDS_LIB"standard"
BODY_TYPE"PLUMBING"
HDL_TAP"TRUE";
"B \NAC \NWC"15;
"S \NAC"
BN"15"107;
%"TAP"
"1","(-800,1800)","0","standard","I64";
;
CDS_LIB"standard"
BODY_TYPE"PLUMBING"
HDL_TAP"TRUE";
"B \NAC \NWC"15;
"S \NAC"
BN"16"108;
%"TAP"
"1","(-800,1950)","0","standard","I65";
;
CDS_LIB"standard"
BODY_TYPE"PLUMBING"
HDL_TAP"TRUE";
"B \NAC \NWC"15;
"S \NAC"
BN"19"111;
%"TAP"
"1","(-800,1900)","0","standard","I66";
;
CDS_LIB"standard"
BODY_TYPE"PLUMBING"
HDL_TAP"TRUE";
"B \NAC \NWC"15;
"S \NAC"
BN"18"110;
%"TAP"
"1","(-800,1850)","0","standard","I67";
;
CDS_LIB"standard"
BODY_TYPE"PLUMBING"
HDL_TAP"TRUE";
"B \NAC \NWC"15;
"S \NAC"
BN"17"109;
%"TAP"
"1","(-800,2050)","0","standard","I68";
;
CDS_LIB"standard"
BODY_TYPE"PLUMBING"
HDL_TAP"TRUE";
"B \NAC \NWC"15;
"S \NAC"
BN"21"113;
%"TAP"
"1","(-800,2000)","0","standard","I69";
;
CDS_LIB"standard"
BODY_TYPE"PLUMBING"
HDL_TAP"TRUE";
"B \NAC \NWC"15;
"S \NAC"
BN"20"112;
%"TAP"
"1","(-800,2200)","0","standard","I70";
;
CDS_LIB"standard"
BODY_TYPE"PLUMBING"
HDL_TAP"TRUE";
"B \NAC \NWC"15;
"S \NAC"
BN"24"80;
%"TAP"
"1","(-800,2150)","0","standard","I71";
;
CDS_LIB"standard"
BODY_TYPE"PLUMBING"
HDL_TAP"TRUE";
"B \NAC \NWC"15;
"S \NAC"
BN"23"115;
%"TAP"
"1","(-800,2100)","0","standard","I72";
;
CDS_LIB"standard"
BODY_TYPE"PLUMBING"
HDL_TAP"TRUE";
"B \NAC \NWC"15;
"S \NAC"
BN"22"114;
%"TAP"
"1","(-800,2250)","0","standard","I73";
;
CDS_LIB"standard"
BODY_TYPE"PLUMBING"
HDL_TAP"TRUE";
"B \NAC \NWC"15;
"S \NAC"
BN"25"79;
%"TAP"
"1","(-800,2300)","0","standard","I74";
;
CDS_LIB"standard"
BODY_TYPE"PLUMBING"
HDL_TAP"TRUE";
"B \NAC \NWC"15;
"S \NAC"
BN"26"116;
%"TAP"
"1","(-800,2450)","0","standard","I75";
;
CDS_LIB"standard"
BODY_TYPE"PLUMBING"
HDL_TAP"TRUE";
"B \NAC \NWC"15;
"S \NAC"
BN"29"119;
%"TAP"
"1","(-800,2400)","0","standard","I76";
;
CDS_LIB"standard"
BODY_TYPE"PLUMBING"
HDL_TAP"TRUE";
"B \NAC \NWC"15;
"S \NAC"
BN"28"118;
%"TAP"
"1","(-800,2350)","0","standard","I77";
;
CDS_LIB"standard"
BODY_TYPE"PLUMBING"
HDL_TAP"TRUE";
"B \NAC \NWC"15;
"S \NAC"
BN"27"117;
%"TAP"
"1","(-800,2500)","0","standard","I78";
;
CDS_LIB"standard"
BODY_TYPE"PLUMBING"
HDL_TAP"TRUE";
"B \NAC \NWC"15;
"S \NAC"
BN"30"120;
%"TAP"
"1","(-800,2550)","0","standard","I79";
;
CDS_LIB"standard"
BODY_TYPE"PLUMBING"
HDL_TAP"TRUE";
"B \NAC \NWC"15;
"S \NAC"
BN"31"121;
%"TAP"
"1","(-800,2650)","0","standard","I80";
;
CDS_LIB"standard"
BODY_TYPE"PLUMBING"
HDL_TAP"TRUE";
"B \NAC \NWC"10;
"S \NAC"
BN"0"122;
%"TAP"
"1","(-800,2700)","0","standard","I81";
;
CDS_LIB"standard"
BODY_TYPE"PLUMBING"
HDL_TAP"TRUE";
"B \NAC \NWC"10;
"S \NAC"
BN"1"78;
%"TAP"
"1","(-800,2800)","0","standard","I82";
;
CDS_LIB"standard"
BODY_TYPE"PLUMBING"
HDL_TAP"TRUE";
"B \NAC \NWC"10;
"S \NAC"
BN"3"124;
%"TAP"
"1","(-800,2750)","0","standard","I83";
;
CDS_LIB"standard"
BODY_TYPE"PLUMBING"
HDL_TAP"TRUE";
"B \NAC \NWC"10;
"S \NAC"
BN"2"123;
%"TAP"
"1","(-800,2850)","0","standard","I84";
;
CDS_LIB"standard"
BODY_TYPE"PLUMBING"
HDL_TAP"TRUE";
"B \NAC \NWC"10;
"S \NAC"
BN"4"125;
%"TAP"
"1","(-800,2900)","0","standard","I85";
;
CDS_LIB"standard"
BODY_TYPE"PLUMBING"
HDL_TAP"TRUE";
"B \NAC \NWC"10;
"S \NAC"
BN"5"126;
%"TAP"
"1","(-800,2950)","0","standard","I86";
;
CDS_LIB"standard"
BODY_TYPE"PLUMBING"
HDL_TAP"TRUE";
"B \NAC \NWC"10;
"S \NAC"
BN"6"127;
%"TAP"
"1","(-800,3000)","0","standard","I87";
;
CDS_LIB"standard"
BODY_TYPE"PLUMBING"
HDL_TAP"TRUE";
"B \NAC \NWC"10;
"S \NAC"
BN"7"128;
%"TAP"
"1","(-800,3050)","0","standard","I88";
;
CDS_LIB"standard"
BODY_TYPE"PLUMBING"
HDL_TAP"TRUE";
"B \NAC \NWC"10;
"S \NAC"
BN"8"129;
%"TAP"
"1","(-800,3100)","0","standard","I89";
;
CDS_LIB"standard"
BODY_TYPE"PLUMBING"
HDL_TAP"TRUE";
"B \NAC \NWC"10;
"S \NAC"
BN"9"75;
%"TAP"
"1","(-800,3150)","0","standard","I90";
;
CDS_LIB"standard"
BODY_TYPE"PLUMBING"
HDL_TAP"TRUE";
"B \NAC \NWC"10;
"S \NAC"
BN"10"130;
%"TAP"
"1","(-800,3200)","0","standard","I91";
;
CDS_LIB"standard"
BODY_TYPE"PLUMBING"
HDL_TAP"TRUE";
"B \NAC \NWC"10;
"S \NAC"
BN"11"131;
%"TAP"
"1","(-800,3250)","0","standard","I92";
;
CDS_LIB"standard"
BODY_TYPE"PLUMBING"
HDL_TAP"TRUE";
"B \NAC \NWC"10;
"S \NAC"
BN"12"132;
%"TAP"
"1","(-800,3350)","0","standard","I93";
;
CDS_LIB"standard"
BODY_TYPE"PLUMBING"
HDL_TAP"TRUE";
"B \NAC \NWC"10;
"S \NAC"
BN"14"68;
%"TAP"
"1","(-800,3300)","0","standard","I94";
;
CDS_LIB"standard"
BODY_TYPE"PLUMBING"
HDL_TAP"TRUE";
"B \NAC \NWC"10;
"S \NAC"
BN"13"74;
%"TAP"
"1","(-800,3450)","0","standard","I95";
;
CDS_LIB"standard"
BODY_TYPE"PLUMBING"
HDL_TAP"TRUE";
"B \NAC \NWC"10;
"S \NAC"
BN"16"134;
%"TAP"
"1","(-800,3400)","0","standard","I96";
;
CDS_LIB"standard"
BODY_TYPE"PLUMBING"
HDL_TAP"TRUE";
"B \NAC \NWC"10;
"S \NAC"
BN"15"133;
%"TAP"
"1","(-800,3600)","0","standard","I97";
;
CDS_LIB"standard"
BODY_TYPE"PLUMBING"
HDL_TAP"TRUE";
"B \NAC \NWC"10;
"S \NAC"
BN"19"135;
%"TAP"
"1","(-800,3550)","0","standard","I98";
;
CDS_LIB"standard"
BODY_TYPE"PLUMBING"
HDL_TAP"TRUE";
"B \NAC \NWC"10;
"S \NAC"
BN"18"77;
%"TAP"
"1","(-800,3500)","0","standard","I99";
;
CDS_LIB"standard"
BODY_TYPE"PLUMBING"
HDL_TAP"TRUE";
"B \NAC \NWC"10;
"S \NAC"
BN"17"69;
END.
